FILE_TYPE = CONNECTIVITY;
{Allegro Design Entry HDL 17.2-2016 S081 (4005846) 1/11/2022}
"PAGE_NUMBER" = 82;
0"NC";
1"GND\g";
2"GND\g";
3"GND\g";
4"GND\g";
5"GND\g";
6"GND\g";
7"GND\g";
8"GND\g";
9"GND\g";
10"GND\g";
11"GND\g";
12"GND\g";
13"GND\g";
14"GND\g";
15"GND\g";
16"GND\g";
17"GND\g";
18"GND\g";
19"GND\g";
20"GND\g";
21"GND\g";
22"GND\g";
23"HPM_BRD_REV_ID1";
24"HPM_BRD_REV_ID2";
25"HPM_BRD_REV_ID0";
26"P1V8_STBY\g";
27"PRSNT1_SLOT1_N";
28"PRSNT2_SLOT1_N";
29"PRSNT1_SLOT2_N";
30"PRSNT2_SLOT2_N";
31"PRSNT_SLOT3_N";
32"PRSNT_N_E1S_1_R";
33"PRSNT_N_E1S_2_R";
34"PRSNT_N_E1S_3_R";
35"RST_SMBMUX_U8_N";
36"RST_SMBMUX_U7_N";
37"P3V3_STBY\g";
38"PVDDCR_CPU1_P0_SMB_ALERT";
39"PVDDCR_CPU0_P1_PMALERT";
40"RM_THROTTLE_N";
41"PRSNT_HDT_N";
42"PVDD11_S3_P1_PMALERT";
43"PVDDCR_CPU1_P1_SMB_ALERT";
44"PVDD11_S3_P0_PMALERT";
45"PVDDCR_CPU0_P0_PMALERT";
46"P1V8_STBY\g";
47"P1V8_STBY\g";
48"PRSNT_N_E1S_4_R";
49"SCM_SYS_PWRBTN_N";
50"P12V_E1S_4_EN_R";
51"P12V_E1S_3_EN_R";
52"P12V_E1S_2_EN_R";
53"P12V_E1S_1_EN_R";
54"FM_SYS_THROTTLE_N"CDS_PHYS_NET_NAME"FM_SYS_THROTTLE_N";
55"P3V3_STBY\g";
56"GND\g";
57"GND\g";
58"PVDD18_S5_P1\g";
59"PVDD18_S5_P0\g";
60"P3V3\g";
61"P3V3_STBY\g";
62"P3V3_E1S_2_EN_R";
63"CPLD_PROGRAMN";
64"HSC_GPIO2_PLD_N";
65"SCM_USB_OC_N";
66"HSC_GPIO1_PLD_N";
67"SMB_SLOT1_ALERT_R_N";
68"SMB_SLOT2_ALERT_R_N";
69"SLOT1_CLKREQ_0_R_N";
70"SLOT1_CLKREQ_1_R_N";
71"SLOT2_CLKREQ_0_R_N";
72"P3V3_E1S_1_EN_R";
73"P3V3_E1S_4_EN_R";
74"P3V3_E1S_3_EN_R";
75"P3V3_OCP_EN_R";
76"P12V_OCP_EN_R";
77"CPLD_JTAG_EN";
78"SLOT2_CLKREQ_1_R_N";
79"FM_P1_PCC1_N";
80"FM_P1_PCC0_N";
81"FM_P0_PCC0_N";
82"FM_P0_PCC1_N";
83"RST_CPU0_KBRST_R_N";
84"FM_CLKREQ_M2_1_N";
85"FM_CLKREQ_M2_2_N";
86"FM_I3C_CPU0_MUX0_OE_N";
87"FM_I3C_CPU0_MUX1_OE_N";
88"FM_I3C_CPU1_MUX0_OE_N";
89"FM_I3C_CPU1_MUX1_OE_N";
90"RST_CPU1_PERST0_N";
91"RST_CPU1_PERST1_N";
92"RST_CPU0_PERST0_N";
93"RST_CPU0_PERST1_N";
94"RST_PERST_E1S_2_N";
95"RST_PERST_E1S_1_N";
96"RST_PERST_E1S_3_N";
97"RST_PERST_M2_1_N";
98"RST_PERST_E1S_4_N";
99"RST_PERST_M2_2_N";
100"RST_PERST_SLOT1_1_N";
101"RST_PERST_SLOT1_0_N";
102"RST_PERST_SLOT2_0_N";
103"RST_PERST_SLOT3_N";
104"RST_PERST_SLOT2_1_N";
%"VCC_CORE"
"1","(-1550,2125)","0","pure_quanta_power","I388";
;
HDL_POWER"P3V3_STBY"
CDS_LIB"pure_quanta_power";
"A"55;
%"GND"
"1","(-350,450)","0","pure_quanta_power","I389";
;
SIZE"1B"
BOM_COST"MEM"
CDS_LIB"pure_quanta_power"
HDL_POWER"GND";
"A<SIZE-1..0>\NAC"56;
%"Q_CAP"
"2","(-1175,1800)","0","pure_quanta","I392";
;
LOCATION"C1171"
$SEC"1"
CDS_SEC"1"
MATERIAL"X7R"
TOLERANCE"10%"
VALUE"0.1UF"
PART_NUMBER"CH4103K1B08"
VOLTAGE"16V"
PACK_TYPE"C0402"
CDS_LIB"pure_quanta";
"A"
$PN"1"55;
"B"
$PN"2"56;
%"Q_CAP"
"2","(-1175,1700)","0","pure_quanta","I393";
;
LOCATION"C1172"
$SEC"1"
CDS_SEC"1"
VALUE"0.1UF"
CDS_LIB"pure_quanta"
MATERIAL"X7R"
TOLERANCE"10%"
PART_NUMBER"CH4103K1B08"
VOLTAGE"16V"
PACK_TYPE"C0402";
"A"
$PN"1"55;
"B"
$PN"2"56;
%"Q_CAP"
"2","(-1175,1600)","0","pure_quanta","I394";
;
LOCATION"C1173"
$SEC"1"
CDS_SEC"1"
VALUE"0.1UF"
CDS_LIB"pure_quanta"
MATERIAL"X7R"
TOLERANCE"10%"
PART_NUMBER"CH4103K1B08"
VOLTAGE"16V"
PACK_TYPE"C0402";
"A"
$PN"1"55;
"B"
$PN"2"56;
%"Q_CAP"
"2","(-1175,1500)","0","pure_quanta","I395";
;
LOCATION"C1174"
$SEC"1"
CDS_SEC"1"
VALUE"0.1UF"
CDS_LIB"pure_quanta"
MATERIAL"X7R"
TOLERANCE"10%"
PART_NUMBER"CH4103K1B08"
VOLTAGE"16V"
PACK_TYPE"C0402";
"A"
$PN"1"55;
"B"
$PN"2"56;
%"Q_CAP"
"2","(-1175,1400)","0","pure_quanta","I396";
;
LOCATION"C1175"
$SEC"1"
CDS_SEC"1"
VALUE"0.1UF"
CDS_LIB"pure_quanta"
MATERIAL"X7R"
TOLERANCE"10%"
PART_NUMBER"CH4103K1B08"
VOLTAGE"16V"
PACK_TYPE"C0402";
"A"
$PN"1"55;
"B"
$PN"2"56;
%"Q_CAP"
"2","(-1175,1300)","0","pure_quanta","I397";
;
LOCATION"C1176"
$SEC"1"
CDS_SEC"1"
VALUE"0.1UF"
CDS_LIB"pure_quanta"
MATERIAL"X7R"
TOLERANCE"10%"
PART_NUMBER"CH4103K1B08"
VOLTAGE"16V"
PACK_TYPE"C0402";
"A"
$PN"1"55;
"B"
$PN"2"56;
%"Q_CAP"
"2","(-1175,1200)","0","pure_quanta","I398";
;
LOCATION"C355"
$SEC"1"
CDS_SEC"1"
VALUE"0.1UF"
CDS_LIB"pure_quanta"
MATERIAL"X7R"
TOLERANCE"10%"
PART_NUMBER"CH4103K1B08"
VOLTAGE"16V"
PACK_TYPE"C0402";
"A"
$PN"1"55;
"B"
$PN"2"56;
%"Q_CAP"
"2","(-1175,1100)","0","pure_quanta","I399";
;
LOCATION"C356"
$SEC"1"
CDS_SEC"1"
VALUE"0.1UF"
CDS_LIB"pure_quanta"
MATERIAL"X7R"
TOLERANCE"10%"
PART_NUMBER"CH4103K1B08"
VOLTAGE"16V"
PACK_TYPE"C0402";
"A"
$PN"1"55;
"B"
$PN"2"56;
%"Q_CAP"
"2","(-1175,1000)","0","pure_quanta","I400";
;
LOCATION"C357"
$SEC"1"
CDS_SEC"1"
VALUE"0.1UF"
CDS_LIB"pure_quanta"
MATERIAL"X7R"
TOLERANCE"10%"
PART_NUMBER"CH4103K1B08"
VOLTAGE"16V"
PACK_TYPE"C0402";
"A"
$PN"1"55;
"B"
$PN"2"56;
%"Q_CAP"
"2","(-1175,900)","0","pure_quanta","I401";
;
LOCATION"C358"
$SEC"1"
CDS_SEC"1"
VALUE"0.1UF"
CDS_LIB"pure_quanta"
MATERIAL"X7R"
TOLERANCE"10%"
PART_NUMBER"CH4103K1B08"
VOLTAGE"16V"
PACK_TYPE"C0402";
"A"
$PN"1"55;
"B"
$PN"2"56;
%"Q_CAP"
"2","(-1175,800)","0","pure_quanta","I402";
;
LOCATION"C359"
$SEC"1"
CDS_SEC"1"
VALUE"0.1UF"
CDS_LIB"pure_quanta"
MATERIAL"X7R"
TOLERANCE"10%"
PART_NUMBER"CH4103K1B08"
VOLTAGE"16V"
PACK_TYPE"C0402";
"A"
$PN"1"55;
"B"
$PN"2"56;
%"Q_CAP"
"2","(-1175,700)","0","pure_quanta","I403";
;
LOCATION"C360"
$SEC"1"
CDS_SEC"1"
VALUE"0.1UF"
CDS_LIB"pure_quanta"
MATERIAL"X7R"
TOLERANCE"10%"
PART_NUMBER"CH4103K1B08"
VOLTAGE"16V"
PACK_TYPE"C0402";
"A"
$PN"1"55;
"B"
$PN"2"56;
%"Q_CAP"
"2","(-1175,600)","0","pure_quanta","I404";
;
LOCATION"C361"
$SEC"1"
CDS_SEC"1"
VALUE"0.1UF"
CDS_LIB"pure_quanta"
MATERIAL"X7R"
TOLERANCE"10%"
PART_NUMBER"CH4103K1B08"
VOLTAGE"16V"
PACK_TYPE"C0402";
"A"
$PN"1"55;
"B"
$PN"2"56;
%"Q_CAP"
"2","(-1175,500)","0","pure_quanta","I405";
;
LOCATION"C362"
$SEC"1"
CDS_SEC"1"
VALUE"0.1UF"
CDS_LIB"pure_quanta"
MATERIAL"X7R"
TOLERANCE"10%"
PART_NUMBER"CH4103K1B08"
VOLTAGE"16V"
PACK_TYPE"C0402";
"A"
$PN"1"55;
"B"
$PN"2"56;
%"GND"
"1","(-2075,650)","0","pure_quanta_power","I406";
;
BOM_COST"MEM"
SIZE"1B"
CDS_LIB"pure_quanta_power"
HDL_POWER"GND";
"A<SIZE-1..0>\NAC"57;
%"Q_CAP"
"2","(-3425,1950)","0","pure_quanta","I407";
;
LOCATION"C1126"
$SEC"1"
CDS_SEC"1"
MATERIAL"X7R"
TOLERANCE"10%"
VALUE"0.1UF"
PART_NUMBER"CH4103K1B08"
VOLTAGE"16V"
PACK_TYPE"C0402"
CDS_LIB"pure_quanta";
"A"
$PN"1"46;
"B"
$PN"2"57;
%"Q_CAP"
"2","(-3425,1750)","0","pure_quanta","I408";
;
LOCATION"C1128"
$SEC"1"
CDS_SEC"1"
VALUE"0.1UF"
CDS_LIB"pure_quanta"
MATERIAL"X7R"
TOLERANCE"10%"
PART_NUMBER"CH4103K1B08"
VOLTAGE"16V"
PACK_TYPE"C0402";
"A"
$PN"1"46;
"B"
$PN"2"57;
%"Q_CAP"
"2","(-3425,1850)","0","pure_quanta","I409";
;
LOCATION"C1127"
$SEC"1"
CDS_SEC"1"
VALUE"0.1UF"
CDS_LIB"pure_quanta"
MATERIAL"X7R"
TOLERANCE"10%"
PART_NUMBER"CH4103K1B08"
VOLTAGE"16V"
PACK_TYPE"C0402";
"A"
$PN"1"46;
"B"
$PN"2"57;
%"Q_CAP"
"2","(-3425,1250)","0","pure_quanta","I411";
;
LOCATION"C1132"
$SEC"1"
CDS_SEC"1"
VALUE"0.1UF"
CDS_LIB"pure_quanta"
MATERIAL"X7R"
TOLERANCE"10%"
PART_NUMBER"CH4103K1B08"
VOLTAGE"16V"
PACK_TYPE"C0402";
"A"
$PN"1"46;
"B"
$PN"2"57;
%"Q_CAP"
"2","(-3425,1350)","0","pure_quanta","I412";
;
LOCATION"C1131"
$SEC"1"
CDS_SEC"1"
VALUE"0.1UF"
CDS_LIB"pure_quanta"
MATERIAL"X7R"
TOLERANCE"10%"
PART_NUMBER"CH4103K1B08"
VOLTAGE"16V"
PACK_TYPE"C0402";
"A"
$PN"1"46;
"B"
$PN"2"57;
%"Q_CAP"
"2","(-3425,1550)","0","pure_quanta","I413";
;
LOCATION"C352"
$SEC"1"
CDS_SEC"1"
VALUE"0.1UF"
CDS_LIB"pure_quanta"
MATERIAL"X7R"
TOLERANCE"10%"
PART_NUMBER"CH4103K1B08"
VOLTAGE"16V"
PACK_TYPE"C0402";
"A"
$PN"1"46;
"B"
$PN"2"57;
%"Q_CAP"
"2","(-3425,1650)","0","pure_quanta","I414";
;
LOCATION"C1129"
$SEC"1"
CDS_SEC"1"
VALUE"0.1UF"
CDS_LIB"pure_quanta"
MATERIAL"X7R"
TOLERANCE"10%"
PART_NUMBER"CH4103K1B08"
VOLTAGE"16V"
PACK_TYPE"C0402";
"A"
$PN"1"46;
"B"
$PN"2"57;
%"Q_CAP"
"2","(-3425,1150)","0","pure_quanta","I415";
;
LOCATION"C1133"
$SEC"1"
CDS_SEC"1"
VALUE"0.1UF"
CDS_LIB"pure_quanta"
MATERIAL"X7R"
TOLERANCE"10%"
PART_NUMBER"CH4103K1B08"
VOLTAGE"16V"
PACK_TYPE"C0402";
"A"
$PN"1"46;
"B"
$PN"2"57;
%"Q_CAP"
"2","(-3425,1050)","0","pure_quanta","I416";
;
LOCATION"C1134"
$SEC"1"
CDS_SEC"1"
VALUE"0.1UF"
CDS_LIB"pure_quanta"
MATERIAL"X7R"
TOLERANCE"10%"
PART_NUMBER"CH4103K1B08"
VOLTAGE"16V"
PACK_TYPE"C0402";
"A"
$PN"1"46;
"B"
$PN"2"57;
%"VCC_CORE"
"1","(-3800,2125)","0","pure_quanta_power","I419";
;
HDL_POWER"P1V8_STBY"
CDS_LIB"pure_quanta_power";
"A"46;
%"GND"
"1","(-3600,4225)","0","pure_quanta_power","I692";
;
BOM_COST"MEM"
SIZE"1B"
CDS_LIB"pure_quanta_power"
HDL_POWER"GND";
"A<SIZE-1..0>\NAC"1;
%"Q_RES"
"2","(-2850,5775)","0","pure_quanta","I708";
;
LOCATION"R19"
$SEC"1"
CDS_SEC"1"
WATTAGE"1/16W"
MATERIAL"CHIP"
TOLERANCE"1%"
VALUE"10K"
PACK_TYPE"0402LF"
CDS_LIB"pure_quanta"
BOM_COST"MEM"
PART_NUMBER"CS31002FB08"
ROOM"MEM_CH_A_CPU0_DIMM1";
"A"
$PN"1"91;
"B"
$PN"2"2;
%"GND"
"1","(-2850,5550)","0","mstr_symbols","I709";
;
BOM_COST"MEM"
SIZE"1B"
CDS_LIB"mstr_symbols"
BODY_TYPE"PLUMBING"
VOLTAGE"0.0"
HDL_POWER"GND";
"A\NAC"2;
%"Q_RES"
"2","(-2325,4450)","0","pure_quanta","I710";
;
LOCATION"R810"
$SEC"1"
CDS_SEC"1"
WATTAGE"1/16W"
MATERIAL"CHIP"
TOLERANCE"1%"
VALUE"10K"
PACK_TYPE"0402LF"
BOM_COST"MEM"
CDS_LIB"pure_quanta"
PART_NUMBER"CS31002FB08"
ROOM"MEM_CH_A_CPU0_DIMM1";
"A"
$PN"1"103;
"B"
$PN"2"3;
%"Q_RES"
"2","(-2450,4450)","0","pure_quanta","I711";
;
LOCATION"R809"
$SEC"1"
CDS_SEC"1"
WATTAGE"1/16W"
MATERIAL"CHIP"
TOLERANCE"1%"
VALUE"10K"
PACK_TYPE"0402LF"
BOM_COST"MEM"
CDS_LIB"pure_quanta"
PART_NUMBER"CS31002FB08"
ROOM"MEM_CH_A_CPU0_DIMM1";
"A"
$PN"1"104;
"B"
$PN"2"4;
%"Q_RES"
"2","(-2575,4450)","0","pure_quanta","I712";
;
LOCATION"R808"
$SEC"1"
CDS_SEC"1"
WATTAGE"1/16W"
MATERIAL"CHIP"
TOLERANCE"1%"
VALUE"10K"
PACK_TYPE"0402LF"
BOM_COST"MEM"
CDS_LIB"pure_quanta"
PART_NUMBER"CS31002FB08"
ROOM"MEM_CH_A_CPU0_DIMM1";
"A"
$PN"1"102;
"B"
$PN"2"5;
%"Q_RES"
"2","(-2700,4450)","0","pure_quanta","I713";
;
LOCATION"R807"
$SEC"1"
CDS_SEC"1"
WATTAGE"1/16W"
MATERIAL"CHIP"
TOLERANCE"1%"
VALUE"10K"
PACK_TYPE"0402LF"
BOM_COST"MEM"
CDS_LIB"pure_quanta"
PART_NUMBER"CS31002FB08"
ROOM"MEM_CH_A_CPU0_DIMM1";
"A"
$PN"1"100;
"B"
$PN"2"6;
%"Q_RES"
"2","(-2825,4450)","0","pure_quanta","I714";
;
LOCATION"R806"
$SEC"1"
CDS_SEC"1"
WATTAGE"1/16W"
MATERIAL"CHIP"
TOLERANCE"1%"
VALUE"10K"
PACK_TYPE"0402LF"
BOM_COST"MEM"
CDS_LIB"pure_quanta"
PART_NUMBER"CS31002FB08"
ROOM"MEM_CH_A_CPU0_DIMM1";
"A"
$PN"1"101;
"B"
$PN"2"7;
%"Q_RES"
"2","(-2975,4450)","0","pure_quanta","I715";
;
LOCATION"R805"
$SEC"1"
CDS_SEC"1"
WATTAGE"1/16W"
MATERIAL"CHIP"
TOLERANCE"1%"
VALUE"10K"
PACK_TYPE"0402LF"
CDS_LIB"pure_quanta"
BOM_COST"MEM"
PART_NUMBER"CS31002FB08"
ROOM"MEM_CH_A_CPU0_DIMM1";
"A"
$PN"1"99;
"B"
$PN"2"8;
%"GND"
"1","(-2325,4225)","0","mstr_symbols","I716";
;
CDS_LIB"mstr_symbols"
SIZE"1B"
BOM_COST"MEM"
BODY_TYPE"PLUMBING"
VOLTAGE"0.0"
HDL_POWER"GND";
"A\NAC"3;
%"GND"
"1","(-2450,4225)","0","mstr_symbols","I717";
;
CDS_LIB"mstr_symbols"
SIZE"1B"
BOM_COST"MEM"
BODY_TYPE"PLUMBING"
VOLTAGE"0.0"
HDL_POWER"GND";
"A\NAC"4;
%"GND"
"1","(-2575,4225)","0","pure_quanta_power","I718";
;
CDS_LIB"pure_quanta_power"
SIZE"1B"
BOM_COST"MEM"
HDL_POWER"GND";
"A<SIZE-1..0>\NAC"5;
%"GND"
"1","(-2700,4225)","0","pure_quanta_power","I719";
;
CDS_LIB"pure_quanta_power"
BOM_COST"MEM"
SIZE"1B"
HDL_POWER"GND";
"A<SIZE-1..0>\NAC"6;
%"GND"
"1","(-2825,4225)","0","pure_quanta_power","I720";
;
CDS_LIB"pure_quanta_power"
SIZE"1B"
BOM_COST"MEM"
HDL_POWER"GND";
"A<SIZE-1..0>\NAC"7;
%"GND"
"1","(-2975,4225)","0","pure_quanta_power","I721";
;
BOM_COST"MEM"
SIZE"1B"
CDS_LIB"pure_quanta_power"
HDL_POWER"GND";
"A<SIZE-1..0>\NAC"8;
%"Q_RES"
"2","(-3075,5775)","0","pure_quanta","I722";
;
LOCATION"R18"
$SEC"1"
CDS_SEC"1"
WATTAGE"1/16W"
MATERIAL"CHIP"
TOLERANCE"1%"
VALUE"10K"
PACK_TYPE"0402LF"
BOM_COST"MEM"
CDS_LIB"pure_quanta"
PART_NUMBER"CS31002FB08"
ROOM"MEM_CH_A_CPU0_DIMM1";
"A"
$PN"1"90;
"B"
$PN"2"9;
%"Q_RES"
"2","(-3275,5775)","0","pure_quanta","I723";
;
LOCATION"R17"
$SEC"1"
CDS_SEC"1"
WATTAGE"1/16W"
MATERIAL"CHIP"
TOLERANCE"1%"
VALUE"10K"
PACK_TYPE"0402LF"
BOM_COST"MEM"
CDS_LIB"pure_quanta"
PART_NUMBER"CS31002FB08"
ROOM"MEM_CH_A_CPU0_DIMM1";
"A"
$PN"1"93;
"B"
$PN"2"10;
%"GND"
"1","(-3075,5550)","0","mstr_symbols","I724";
;
CDS_LIB"mstr_symbols"
BOM_COST"MEM"
SIZE"1B"
BODY_TYPE"PLUMBING"
VOLTAGE"0.0"
HDL_POWER"GND";
"A\NAC"9;
%"GND"
"1","(-3275,5550)","0","pure_quanta_power","I725";
;
CDS_LIB"pure_quanta_power"
SIZE"1B"
BOM_COST"MEM"
HDL_POWER"GND";
"A<SIZE-1..0>\NAC"10;
%"Q_RES"
"2","(-3475,5775)","0","pure_quanta","I726";
;
LOCATION"R16"
$SEC"1"
CDS_SEC"1"
WATTAGE"1/16W"
MATERIAL"CHIP"
TOLERANCE"1%"
VALUE"10K"
PACK_TYPE"0402LF"
BOM_COST"MEM"
CDS_LIB"pure_quanta"
PART_NUMBER"CS31002FB08"
ROOM"MEM_CH_A_CPU0_DIMM1";
"A"
$PN"1"92;
"B"
$PN"2"11;
%"GND"
"1","(-3475,5550)","0","pure_quanta_power","I727";
;
CDS_LIB"pure_quanta_power"
SIZE"1B"
BOM_COST"MEM"
HDL_POWER"GND";
"A<SIZE-1..0>\NAC"11;
%"Q_RES"
"2","(-3100,4450)","0","pure_quanta","I728";
;
LOCATION"R804"
$SEC"1"
CDS_SEC"1"
WATTAGE"1/16W"
MATERIAL"CHIP"
TOLERANCE"1%"
VALUE"10K"
PACK_TYPE"0402LF"
CDS_LIB"pure_quanta"
BOM_COST"MEM"
PART_NUMBER"CS31002FB08"
ROOM"MEM_CH_A_CPU0_DIMM1";
"A"
$PN"1"97;
"B"
$PN"2"12;
%"Q_RES"
"2","(-3225,4450)","0","pure_quanta","I729";
;
LOCATION"R803"
$SEC"1"
CDS_SEC"1"
WATTAGE"1/16W"
MATERIAL"CHIP"
TOLERANCE"1%"
VALUE"10K"
PACK_TYPE"0402LF"
CDS_LIB"pure_quanta"
BOM_COST"MEM"
PART_NUMBER"CS31002FB08"
ROOM"MEM_CH_A_CPU0_DIMM1";
"A"
$PN"1"98;
"B"
$PN"2"13;
%"Q_RES"
"2","(-3350,4450)","0","pure_quanta","I730";
;
LOCATION"R802"
$SEC"1"
CDS_SEC"1"
WATTAGE"1/16W"
MATERIAL"CHIP"
TOLERANCE"1%"
VALUE"10K"
PACK_TYPE"0402LF"
CDS_LIB"pure_quanta"
BOM_COST"MEM"
PART_NUMBER"CS31002FB08"
ROOM"MEM_CH_A_CPU0_DIMM1";
"A"
$PN"1"96;
"B"
$PN"2"15;
%"Q_RES"
"2","(-3475,4450)","0","pure_quanta","I731";
;
LOCATION"R801"
$SEC"1"
CDS_SEC"1"
WATTAGE"1/16W"
MATERIAL"CHIP"
TOLERANCE"1%"
VALUE"10K"
PACK_TYPE"0402LF"
CDS_LIB"pure_quanta"
BOM_COST"MEM"
PART_NUMBER"CS31002FB08"
ROOM"MEM_CH_A_CPU0_DIMM1";
"A"
$PN"1"94;
"B"
$PN"2"14;
%"Q_RES"
"2","(-3600,4450)","0","pure_quanta","I732";
;
LOCATION"R800"
$SEC"1"
CDS_SEC"1"
WATTAGE"1/16W"
MATERIAL"CHIP"
TOLERANCE"1%"
VALUE"10K"
PACK_TYPE"0402LF"
CDS_LIB"pure_quanta"
BOM_COST"MEM"
PART_NUMBER"CS31002FB08"
ROOM"MEM_CH_A_CPU0_DIMM1";
"A"
$PN"1"95;
"B"
$PN"2"1;
%"GND"
"1","(-3100,4225)","0","mstr_symbols","I733";
;
BOM_COST"MEM"
SIZE"1B"
CDS_LIB"mstr_symbols"
BODY_TYPE"PLUMBING"
VOLTAGE"0.0"
HDL_POWER"GND";
"A\NAC"12;
%"GND"
"1","(-3225,4225)","0","mstr_symbols","I734";
;
BOM_COST"MEM"
SIZE"1B"
CDS_LIB"mstr_symbols"
BODY_TYPE"PLUMBING"
VOLTAGE"0.0"
HDL_POWER"GND";
"A\NAC"13;
%"GND"
"1","(-3475,4225)","0","pure_quanta_power","I735";
;
SIZE"1B"
BOM_COST"MEM"
CDS_LIB"pure_quanta_power"
HDL_POWER"GND";
"A<SIZE-1..0>\NAC"14;
%"GND"
"1","(-3350,4225)","0","pure_quanta_power","I736";
;
BOM_COST"MEM"
SIZE"1B"
CDS_LIB"pure_quanta_power"
HDL_POWER"GND";
"A<SIZE-1..0>\NAC"15;
%"VCC_CORE"
"1","(-4625,6000)","0","pure_quanta_power","I737";
;
HDL_POWER"PVDD18_S5_P1"
CDS_LIB"pure_quanta_power";
"A"58;
%"VCC_CORE"
"1","(-4625,5525)","0","pure_quanta_power","I738";
;
HDL_POWER"PVDD18_S5_P0"
CDS_LIB"pure_quanta_power";
"A"59;
%"VCC_CORE"
"1","(-4600,5025)","0","pure_quanta_power","I739";
;
HDL_POWER"P3V3"
CDS_LIB"pure_quanta_power";
"A"60;
%"Q_RES"
"1","(-4900,5875)","0","pure_quanta","I740";
;
LOCATION"R1285"
$SEC"1"
CDS_SEC"1"
VALUE"4.7K"
CDS_LIB"pure_quanta"
WATTAGE"1/16W"
MATERIAL"CHIP"
TOLERANCE"5%"
PART_NUMBER"TMP_QCS24702JB38"
PACK_TYPE"0402LF";
"B"
$PN"2"58;
"A"
$PN"1"80;
%"Q_RES"
"1","(-4900,5825)","0","pure_quanta","I741";
;
LOCATION"R1286"
$SEC"1"
CDS_SEC"1"
VALUE"4.7K"
CDS_LIB"pure_quanta"
WATTAGE"1/16W"
MATERIAL"CHIP"
TOLERANCE"5%"
PART_NUMBER"TMP_QCS24702JB38"
PACK_TYPE"0402LF";
"B"
$PN"2"58;
"A"
$PN"1"79;
%"Q_RES"
"1","(-4900,5375)","0","pure_quanta","I742";
;
LOCATION"R1287"
$SEC"1"
CDS_SEC"1"
VALUE"4.7K"
CDS_LIB"pure_quanta"
WATTAGE"1/16W"
MATERIAL"CHIP"
TOLERANCE"5%"
PART_NUMBER"TMP_QCS24702JB38"
PACK_TYPE"0402LF";
"B"
$PN"2"59;
"A"
$PN"1"81;
%"Q_RES"
"1","(-4900,5325)","0","pure_quanta","I743";
;
LOCATION"R1288"
$SEC"1"
CDS_SEC"1"
VALUE"4.7K"
CDS_LIB"pure_quanta"
WATTAGE"1/16W"
MATERIAL"CHIP"
TOLERANCE"5%"
PART_NUMBER"TMP_QCS24702JB38"
PACK_TYPE"0402LF";
"B"
$PN"2"59;
"A"
$PN"1"82;
%"Q_RES"
"1","(-4900,5250)","0","pure_quanta","I744";
;
LOCATION"R1351"
$SEC"1"
CDS_SEC"1"
VALUE"2.2K"
CDS_LIB"pure_quanta"
WATTAGE"1/16W"
MATERIAL"CHIP"
TOLERANCE"5%"
PART_NUMBER"CS22202JB07"
PACK_TYPE"0402LF";
"B"
$PN"2"59;
"A"
$PN"1"83;
%"Q_RES"
"1","(-4900,4475)","0","pure_quanta","I745";
;
LOCATION"R1191"
$SEC"1"
CDS_SEC"1"
VALUE"4.7K"
CDS_LIB"pure_quanta"
WATTAGE"1/16W"
MATERIAL"CHIP"
TOLERANCE"5%"
PART_NUMBER"TMP_QCS24702JB38"
PACK_TYPE"0402LF";
"B"
$PN"2"60;
"A"
$PN"1"84;
%"Q_RES"
"1","(-4900,4425)","0","pure_quanta","I746";
;
LOCATION"R1192"
$SEC"1"
CDS_SEC"1"
VALUE"4.7K"
CDS_LIB"pure_quanta"
WATTAGE"1/16W"
MATERIAL"CHIP"
TOLERANCE"5%"
PART_NUMBER"TMP_QCS24702JB38"
PACK_TYPE"0402LF";
"B"
$PN"2"60;
"A"
$PN"1"85;
%"VCC_CORE"
"1","(-6800,6350)","0","pure_quanta_power","I749";
;
HDL_POWER"P1V8_STBY"
CDS_LIB"pure_quanta_power";
"A"47;
%"VCC_CORE"
"1","(-6775,5625)","0","pure_quanta_power","I750";
;
HDL_POWER"P3V3_STBY"
CDS_LIB"pure_quanta_power";
"A"37;
%"Q_RES"
"1","(-7025,5825)","0","pure_quanta","I756";
;
LOCATION"R960"
$SEC"1"
CDS_SEC"1"
VALUE"4.7K"
CDS_LIB"pure_quanta"
WATTAGE"1/16W"
MATERIAL"CHIP"
TOLERANCE"5%"
PART_NUMBER"TMP_QCS24702JB38"
PACK_TYPE"0402LF";
"B"
$PN"2"47;
"A"
$PN"1"66;
%"Q_RES"
"1","(-7025,5775)","0","pure_quanta","I757";
;
LOCATION"R961"
$SEC"1"
CDS_SEC"1"
VALUE"4.7K"
CDS_LIB"pure_quanta"
WATTAGE"1/16W"
MATERIAL"CHIP"
TOLERANCE"5%"
PART_NUMBER"TMP_QCS24702JB38"
PACK_TYPE"0402LF";
"B"
$PN"2"47;
"A"
$PN"1"64;
%"Q_RES"
"1","(-7025,5725)","0","pure_quanta","I758";
;
LOCATION"R654"
$SEC"1"
CDS_SEC"1"
VALUE"4.7K"
CDS_LIB"pure_quanta"
WATTAGE"1/16W"
MATERIAL"CHIP"
TOLERANCE"5%"
PART_NUMBER"TMP_QCS24702JB38"
PACK_TYPE"0402LF";
"B"
$PN"2"47;
"A"
$PN"1"65;
%"Q_RES"
"1","(-7025,5550)","0","pure_quanta","I759";
;
LOCATION"R1185"
$SEC"1"
CDS_SEC"1"
VALUE"4.7K"
CDS_LIB"pure_quanta"
WATTAGE"1/16W"
MATERIAL"CHIP"
TOLERANCE"5%"
PART_NUMBER"TMP_QCS24702JB38"
PACK_TYPE"0402LF";
"B"
$PN"2"37;
"A"
$PN"1"45;
%"Q_RES"
"1","(-7025,5350)","0","pure_quanta","I760";
;
LOCATION"R1189"
$SEC"1"
CDS_SEC"1"
VALUE"4.7K"
CDS_LIB"pure_quanta"
WATTAGE"1/16W"
MATERIAL"CHIP"
TOLERANCE"5%"
PART_NUMBER"TMP_QCS24702JB38"
PACK_TYPE"0402LF";
"B"
$PN"2"37;
"A"
$PN"1"44;
%"Q_RES"
"1","(-7025,5400)","0","pure_quanta","I761";
;
LOCATION"R1188"
$SEC"1"
CDS_SEC"1"
VALUE"4.7K"
CDS_LIB"pure_quanta"
WATTAGE"1/16W"
MATERIAL"CHIP"
TOLERANCE"5%"
PART_NUMBER"TMP_QCS24702JB38"
PACK_TYPE"0402LF";
"B"
$PN"2"37;
"A"
$PN"1"43;
%"Q_RES"
"1","(-7025,5500)","0","pure_quanta","I762";
;
LOCATION"R1186"
$SEC"1"
CDS_SEC"1"
VALUE"4.7K"
CDS_LIB"pure_quanta"
WATTAGE"1/16W"
MATERIAL"CHIP"
TOLERANCE"5%"
PART_NUMBER"TMP_QCS24702JB38"
PACK_TYPE"0402LF";
"B"
$PN"2"37;
"A"
$PN"1"38;
%"Q_RES"
"1","(-7025,5300)","0","pure_quanta","I763";
;
LOCATION"R1190"
$SEC"1"
CDS_SEC"1"
VALUE"4.7K"
CDS_LIB"pure_quanta"
WATTAGE"1/16W"
MATERIAL"CHIP"
TOLERANCE"5%"
PART_NUMBER"TMP_QCS24702JB38"
PACK_TYPE"0402LF";
"B"
$PN"2"37;
"A"
$PN"1"42;
%"Q_RES"
"1","(-7025,5450)","0","pure_quanta","I764";
;
LOCATION"R1187"
$SEC"1"
CDS_SEC"1"
VALUE"4.7K"
CDS_LIB"pure_quanta"
WATTAGE"1/16W"
MATERIAL"CHIP"
TOLERANCE"5%"
PART_NUMBER"TMP_QCS24702JB38"
PACK_TYPE"0402LF";
"B"
$PN"2"37;
"A"
$PN"1"39;
%"Q_RES"
"1","(-7025,5100)","0","pure_quanta","I765";
;
LOCATION"R668"
$SEC"1"
CDS_SEC"1"
VALUE"4.7K"
CDS_LIB"pure_quanta"
WATTAGE"1/16W"
MATERIAL"CHIP"
TOLERANCE"5%"
PART_NUMBER"TMP_QCS24702JB38"
PACK_TYPE"0402LF";
"B"
$PN"2"37;
"A"
$PN"1"40;
%"Q_RES"
"1","(-7025,4675)","0","pure_quanta","I768";
;
LOCATION"R1181"
$SEC"1"
CDS_SEC"1"
VALUE"4.7K"
CDS_LIB"pure_quanta"
WATTAGE"1/16W"
MATERIAL"CHIP"
TOLERANCE"5%"
PART_NUMBER"TMP_QCS24702JB38"
PACK_TYPE"0402LF";
"B"
$PN"2"37;
"A"
$PN"1"30;
%"Q_RES"
"1","(-7025,4725)","0","pure_quanta","I769";
;
LOCATION"R1180"
$SEC"1"
CDS_SEC"1"
VALUE"4.7K"
CDS_LIB"pure_quanta"
WATTAGE"1/16W"
MATERIAL"CHIP"
TOLERANCE"5%"
PART_NUMBER"TMP_QCS24702JB38"
PACK_TYPE"0402LF";
"B"
$PN"2"37;
"A"
$PN"1"29;
%"Q_RES"
"1","(-7025,4975)","0","pure_quanta","I770";
;
LOCATION"R656"
$SEC"1"
CDS_SEC"1"
VALUE"4.7K"
CDS_LIB"pure_quanta"
WATTAGE"1/16W"
MATERIAL"CHIP"
TOLERANCE"5%"
PART_NUMBER"TMP_QCS24702JB38"
PACK_TYPE"0402LF";
"B"
$PN"2"37;
"A"
$PN"1"35;
%"Q_RES"
"1","(-7025,5025)","0","pure_quanta","I771";
;
LOCATION"R655"
$SEC"1"
CDS_SEC"1"
VALUE"4.7K"
CDS_LIB"pure_quanta"
WATTAGE"1/16W"
MATERIAL"CHIP"
TOLERANCE"5%"
PART_NUMBER"TMP_QCS24702JB38"
PACK_TYPE"0402LF";
"B"
$PN"2"37;
"A"
$PN"1"36;
%"Q_RES"
"1","(-7025,4625)","0","pure_quanta","I772";
;
LOCATION"R1182"
$SEC"1"
CDS_SEC"1"
VALUE"4.7K"
CDS_LIB"pure_quanta"
WATTAGE"1/16W"
MATERIAL"CHIP"
TOLERANCE"5%"
PART_NUMBER"TMP_QCS24702JB38"
PACK_TYPE"0402LF";
"B"
$PN"2"37;
"A"
$PN"1"31;
%"Q_RES"
"1","(-7025,4400)","0","pure_quanta","I773";
;
LOCATION"R1307"
$SEC"1"
CDS_SEC"1"
VALUE"4.7K"
CDS_LIB"pure_quanta"
WATTAGE"1/16W"
MATERIAL"CHIP"
TOLERANCE"5%"
PART_NUMBER"TMP_QCS24702JB38"
PACK_TYPE"0402LF";
"B"
$PN"2"37;
"A"
$PN"1"48;
%"Q_RES"
"1","(-7025,4450)","0","pure_quanta","I774";
;
LOCATION"R1306"
$SEC"1"
CDS_SEC"1"
VALUE"4.7K"
CDS_LIB"pure_quanta"
WATTAGE"1/16W"
MATERIAL"CHIP"
TOLERANCE"5%"
PART_NUMBER"TMP_QCS24702JB38"
PACK_TYPE"0402LF";
"B"
$PN"2"37;
"A"
$PN"1"34;
%"Q_RES"
"1","(-7025,4500)","0","pure_quanta","I775";
;
LOCATION"R1305"
$SEC"1"
CDS_SEC"1"
VALUE"4.7K"
CDS_LIB"pure_quanta"
WATTAGE"1/16W"
MATERIAL"CHIP"
TOLERANCE"5%"
PART_NUMBER"TMP_QCS24702JB38"
PACK_TYPE"0402LF";
"B"
$PN"2"37;
"A"
$PN"1"33;
%"Q_RES"
"1","(-7025,4550)","0","pure_quanta","I776";
;
LOCATION"R1304"
$SEC"1"
CDS_SEC"1"
VALUE"4.7K"
CDS_LIB"pure_quanta"
WATTAGE"1/16W"
MATERIAL"CHIP"
TOLERANCE"5%"
PART_NUMBER"TMP_QCS24702JB38"
PACK_TYPE"0402LF";
"B"
$PN"2"37;
"A"
$PN"1"32;
%"Q_RES"
"1","(-7025,4175)","0","pure_quanta","I777";
;
LOCATION"R1314"
$SEC"1"
CDS_SEC"1"
MATERIAL"EMPTY"
VALUE"4.7K"
CDS_LIB"pure_quanta"
WATTAGE"1/16W"
TOLERANCE"5%"
PART_NUMBER"TMP_QCS24702JB38"
PACK_TYPE"0402LF";
"B"
$PN"2"37;
"A"
$PN"1"53;
%"Q_RES"
"1","(-7025,4125)","0","pure_quanta","I778";
;
LOCATION"R1315"
$SEC"1"
CDS_SEC"1"
VALUE"4.7K"
MATERIAL"EMPTY"
CDS_LIB"pure_quanta"
WATTAGE"1/16W"
TOLERANCE"5%"
PART_NUMBER"TMP_QCS24702JB38"
PACK_TYPE"0402LF";
"B"
$PN"2"37;
"A"
$PN"1"52;
%"Q_RES"
"1","(-7025,4300)","0","pure_quanta","I779";
;
LOCATION"R993"
$SEC"1"
CDS_SEC"1"
VALUE"4.7K"
CDS_LIB"pure_quanta"
WATTAGE"1/16W"
MATERIAL"CHIP"
TOLERANCE"5%"
PART_NUMBER"TMP_QCS24702JB38"
PACK_TYPE"0402LF";
"B"
$PN"2"37;
"A"
$PN"1"54;
%"Q_RES"
"1","(-7025,4075)","0","pure_quanta","I780";
;
LOCATION"R1316"
$SEC"1"
CDS_SEC"1"
VALUE"4.7K"
MATERIAL"EMPTY"
CDS_LIB"pure_quanta"
WATTAGE"1/16W"
TOLERANCE"5%"
PART_NUMBER"TMP_QCS24702JB38"
PACK_TYPE"0402LF";
"B"
$PN"2"37;
"A"
$PN"1"51;
%"Q_RES"
"1","(-7025,4025)","0","pure_quanta","I781";
;
LOCATION"R1317"
$SEC"1"
CDS_SEC"1"
MATERIAL"EMPTY"
VALUE"4.7K"
CDS_LIB"pure_quanta"
WATTAGE"1/16W"
TOLERANCE"5%"
PART_NUMBER"TMP_QCS24702JB38"
PACK_TYPE"0402LF";
"B"
$PN"2"37;
"A"
$PN"1"50;
%"Q_RES"
"1","(-7025,3925)","0","pure_quanta","I782";
;
LOCATION"R757"
$SEC"1"
CDS_SEC"1"
MATERIAL"EMPTY"
VALUE"4.7K"
CDS_LIB"pure_quanta"
WATTAGE"1/16W"
TOLERANCE"5%"
PART_NUMBER"TMP_QCS24702JB38"
PACK_TYPE"0402LF";
"B"
$PN"2"37;
"A"
$PN"1"72;
%"Q_RES"
"1","(-7025,3875)","0","pure_quanta","I783";
;
LOCATION"R758"
$SEC"1"
CDS_SEC"1"
MATERIAL"EMPTY"
VALUE"4.7K"
CDS_LIB"pure_quanta"
WATTAGE"1/16W"
TOLERANCE"5%"
PART_NUMBER"TMP_QCS24702JB38"
PACK_TYPE"0402LF";
"B"
$PN"2"37;
"A"
$PN"1"62;
%"Q_RES"
"1","(-7025,3825)","0","pure_quanta","I784";
;
LOCATION"R759"
$SEC"1"
CDS_SEC"1"
MATERIAL"EMPTY"
VALUE"4.7K"
CDS_LIB"pure_quanta"
WATTAGE"1/16W"
TOLERANCE"5%"
PART_NUMBER"TMP_QCS24702JB38"
PACK_TYPE"0402LF";
"B"
$PN"2"37;
"A"
$PN"1"74;
%"Q_RES"
"1","(-7025,3775)","0","pure_quanta","I785";
;
LOCATION"R951"
$SEC"1"
CDS_SEC"1"
MATERIAL"EMPTY"
VALUE"4.7K"
CDS_LIB"pure_quanta"
WATTAGE"1/16W"
TOLERANCE"5%"
PART_NUMBER"TMP_QCS24702JB38"
PACK_TYPE"0402LF";
"B"
$PN"2"37;
"A"
$PN"1"73;
%"Q_RES"
"1","(-7025,3625)","0","pure_quanta","I795";
;
LOCATION"R1071"
$SEC"1"
CDS_SEC"1"
MATERIAL"EMPTY"
VALUE"4.7K"
CDS_LIB"pure_quanta"
WATTAGE"1/16W"
TOLERANCE"5%"
PART_NUMBER"TMP_QCS24702JB38"
PACK_TYPE"0402LF";
"B"
$PN"2"37;
"A"
$PN"1"75;
%"Q_RES"
"1","(-7025,3575)","0","pure_quanta","I796";
;
LOCATION"R1195"
$SEC"1"
CDS_SEC"1"
MATERIAL"EMPTY"
VALUE"4.7K"
CDS_LIB"pure_quanta"
WATTAGE"1/16W"
TOLERANCE"5%"
PART_NUMBER"TMP_QCS24702JB38"
PACK_TYPE"0402LF";
"B"
$PN"2"37;
"A"
$PN"1"76;
%"Q_RES"
"1","(-7025,5875)","0","pure_quanta","I839";
;
LOCATION"R1520"
$SEC"1"
CDS_SEC"1"
VALUE"4.7K"
CDS_LIB"pure_quanta"
WATTAGE"1/16W"
MATERIAL"CHIP"
TOLERANCE"5%"
PART_NUMBER"TMP_QCS24702JB38"
PACK_TYPE"0402LF";
"B"
$PN"2"47;
"A"
$PN"1"67;
%"Q_RES"
"1","(-7025,5925)","0","pure_quanta","I840";
;
LOCATION"R1519"
$SEC"1"
CDS_SEC"1"
VALUE"4.7K"
CDS_LIB"pure_quanta"
WATTAGE"1/16W"
MATERIAL"CHIP"
TOLERANCE"5%"
PART_NUMBER"TMP_QCS24702JB38"
PACK_TYPE"0402LF";
"B"
$PN"2"47;
"A"
$PN"1"68;
%"Q_RES"
"1","(-7025,5975)","0","pure_quanta","I841";
;
LOCATION"R1518"
$SEC"1"
CDS_SEC"1"
VALUE"4.7K"
CDS_LIB"pure_quanta"
WATTAGE"1/16W"
MATERIAL"CHIP"
TOLERANCE"5%"
PART_NUMBER"TMP_QCS24702JB38"
PACK_TYPE"0402LF";
"B"
$PN"2"47;
"A"
$PN"1"69;
%"Q_RES"
"1","(-7025,6025)","0","pure_quanta","I842";
;
LOCATION"R1517"
$SEC"1"
CDS_SEC"1"
VALUE"4.7K"
CDS_LIB"pure_quanta"
WATTAGE"1/16W"
MATERIAL"CHIP"
TOLERANCE"5%"
PART_NUMBER"TMP_QCS24702JB38"
PACK_TYPE"0402LF";
"B"
$PN"2"47;
"A"
$PN"1"70;
%"Q_RES"
"1","(-7025,6075)","0","pure_quanta","I843";
;
LOCATION"R1516"
$SEC"1"
CDS_SEC"1"
VALUE"4.7K"
CDS_LIB"pure_quanta"
WATTAGE"1/16W"
MATERIAL"CHIP"
TOLERANCE"5%"
PART_NUMBER"TMP_QCS24702JB38"
PACK_TYPE"0402LF";
"B"
$PN"2"47;
"A"
$PN"1"71;
%"Q_RES"
"1","(-7025,6125)","0","pure_quanta","I844";
;
LOCATION"R1515"
$SEC"1"
CDS_SEC"1"
VALUE"4.7K"
CDS_LIB"pure_quanta"
WATTAGE"1/16W"
MATERIAL"CHIP"
TOLERANCE"5%"
PART_NUMBER"TMP_QCS24702JB38"
PACK_TYPE"0402LF";
"B"
$PN"2"47;
"A"
$PN"1"78;
%"Q_RES"
"1","(-7050,2975)","0","pure_quanta","I909";
;
LOCATION"R64"
$SEC"1"
CDS_SEC"1"
VALUE"1K"
CDS_LIB"pure_quanta"
WATTAGE"1/16W"
MATERIAL"CHIP"
TOLERANCE"5%"
PART_NUMBER"TMP_QCS21002JB34"
PACK_TYPE"0402LF";
"B"
$PN"2"61;
"A"
$PN"1"49;
%"Q_RES"
"1","(-7050,3100)","0","pure_quanta","I910";
;
LOCATION"R638"
$SEC"1"
CDS_SEC"1"
VALUE"1K"
CDS_LIB"pure_quanta"
WATTAGE"1/16W"
MATERIAL"CHIP"
TOLERANCE"5%"
PART_NUMBER"TMP_QCS21002JB34"
PACK_TYPE"0402LF";
"B"
$PN"2"61;
"A"
$PN"1"77;
%"Q_RES"
"1","(-7050,3050)","0","pure_quanta","I911";
;
LOCATION"R639"
$SEC"1"
CDS_SEC"1"
VALUE"1K"
CDS_LIB"pure_quanta"
WATTAGE"1/16W"
MATERIAL"CHIP"
TOLERANCE"5%"
PART_NUMBER"TMP_QCS21002JB34"
PACK_TYPE"0402LF";
"B"
$PN"2"61;
"A"
$PN"1"63;
%"GND"
"1","(-3050,3000)","0","pure_quanta_power","I932";
;
SIZE"1B"
BOM_COST"MEM"
CDS_LIB"pure_quanta_power"
HDL_POWER"GND";
"A<SIZE-1..0>\NAC"16;
%"Q_RES"
"2","(-3050,3225)","0","pure_quanta","I933";
;
LOCATION"R25"
$SEC"1"
CDS_SEC"1"
WATTAGE"1/16W"
MATERIAL"CHIP"
TOLERANCE"1%"
VALUE"10K"
PACK_TYPE"0402LF"
CDS_LIB"pure_quanta"
BOM_COST"MEM"
PART_NUMBER"CS31002FB08"
ROOM"MEM_CH_A_CPU0_DIMM1";
"A"
$PN"1"89;
"B"
$PN"2"16;
%"Q_RES"
"2","(-3275,3225)","0","pure_quanta","I934";
;
LOCATION"R12"
$SEC"1"
CDS_SEC"1"
WATTAGE"1/16W"
MATERIAL"CHIP"
TOLERANCE"1%"
VALUE"10K"
PACK_TYPE"0402LF"
CDS_LIB"pure_quanta"
BOM_COST"MEM"
PART_NUMBER"CS31002FB08"
ROOM"MEM_CH_A_CPU0_DIMM1";
"A"
$PN"1"88;
"B"
$PN"2"17;
%"GND"
"1","(-3275,3000)","0","pure_quanta_power","I935";
;
SIZE"1B"
BOM_COST"MEM"
CDS_LIB"pure_quanta_power"
HDL_POWER"GND";
"A<SIZE-1..0>\NAC"17;
%"Q_RES"
"2","(-3475,3225)","0","pure_quanta","I936";
;
LOCATION"R11"
$SEC"1"
CDS_SEC"1"
WATTAGE"1/16W"
MATERIAL"CHIP"
TOLERANCE"1%"
VALUE"10K"
PACK_TYPE"0402LF"
CDS_LIB"pure_quanta"
BOM_COST"MEM"
PART_NUMBER"CS31002FB08"
ROOM"MEM_CH_A_CPU0_DIMM1";
"A"
$PN"1"87;
"B"
$PN"2"18;
%"GND"
"1","(-3475,3000)","0","pure_quanta_power","I937";
;
BOM_COST"MEM"
SIZE"1B"
CDS_LIB"pure_quanta_power"
HDL_POWER"GND";
"A<SIZE-1..0>\NAC"18;
%"GND"
"1","(-3675,3000)","0","pure_quanta_power","I938";
;
SIZE"1B"
BOM_COST"MEM"
CDS_LIB"pure_quanta_power"
HDL_POWER"GND";
"A<SIZE-1..0>\NAC"19;
%"Q_RES"
"2","(-3675,3225)","0","pure_quanta","I939";
;
LOCATION"R10"
$SEC"1"
CDS_SEC"1"
WATTAGE"1/16W"
MATERIAL"CHIP"
TOLERANCE"1%"
VALUE"10K"
PACK_TYPE"0402LF"
CDS_LIB"pure_quanta"
BOM_COST"MEM"
PART_NUMBER"CS31002FB08"
ROOM"MEM_CH_A_CPU0_DIMM1";
"A"
$PN"1"86;
"B"
$PN"2"19;
%"UNIVERSAL_POWER"
"1","(-6775,3300)","2","pure_quanta_power","I940";
;
HDL_POWER"P3V3_STBY"
CDS_LIB"pure_quanta_power";
"A"61;
%"VCC_CORE"
"1","(-7050,2025)","0","pure_quanta_power","I944";
;
HDL_POWER"P1V8_STBY"
CDS_LIB"pure_quanta_power";
"A"26;
%"Q_RES"
"2","(-7050,1700)","0","pure_quanta","I945";
;
LOCATION"R1525"
$SEC"1"
CDS_SEC"1"
VALUE"4.7K"
MATERIAL"EMPTY"
CDS_LIB"pure_quanta"
WATTAGE"1/16W"
TOLERANCE"5%"
PART_NUMBER"TMP_QCS24702JB38"
PACK_TYPE"0402LF";
"A"
$PN"1"26;
"B"
$PN"2"24;
%"Q_RES"
"2","(-7300,1700)","0","pure_quanta","I946";
;
LOCATION"R752"
$SEC"1"
CDS_SEC"1"
VALUE"4.7K"
PACK_TYPE"0402LF"
PART_NUMBER"TMP_QCS24702JB38"
TOLERANCE"5%"
WATTAGE"1/16W"
CDS_LIB"pure_quanta"
MATERIAL"CHIP";
"A"
$PN"1"26;
"B"
$PN"2"23;
%"Q_RES"
"2","(-7575,1700)","0","pure_quanta","I947";
;
LOCATION"R741"
$SEC"1"
CDS_SEC"1"
VALUE"4.7K"
MATERIAL"EMPTY"
PACK_TYPE"0402LF"
PART_NUMBER"TMP_QCS24702JB38"
TOLERANCE"5%"
WATTAGE"1/16W"
CDS_LIB"pure_quanta";
"A"
$PN"1"26;
"B"
$PN"2"25;
%"Q_RES"
"2","(-7050,1200)","0","pure_quanta","I948";
;
LOCATION"R1526"
$SEC"1"
CDS_SEC"1"
VALUE"4.7K"
CDS_LIB"pure_quanta"
WATTAGE"1/16W"
MATERIAL"CHIP"
TOLERANCE"5%"
PART_NUMBER"TMP_QCS24702JB38"
PACK_TYPE"0402LF";
"A"
$PN"1"24;
"B"
$PN"2"22;
%"Q_RES"
"2","(-7300,1200)","0","pure_quanta","I949";
;
LOCATION"R1524"
$SEC"1"
CDS_SEC"1"
MATERIAL"EMPTY"
VALUE"4.7K"
PACK_TYPE"0402LF"
PART_NUMBER"TMP_QCS24702JB38"
TOLERANCE"5%"
WATTAGE"1/16W"
CDS_LIB"pure_quanta";
"A"
$PN"1"23;
"B"
$PN"2"21;
%"Q_RES"
"2","(-7575,1200)","0","pure_quanta","I950";
;
LOCATION"R749"
$SEC"1"
CDS_SEC"1"
VALUE"4.7K"
PACK_TYPE"0402LF"
PART_NUMBER"TMP_QCS24702JB38"
TOLERANCE"5%"
WATTAGE"1/16W"
CDS_LIB"pure_quanta"
MATERIAL"CHIP";
"A"
$PN"1"25;
"B"
$PN"2"20;
%"GND"
"1","(-7575,975)","0","pure_quanta_power","I951";
;
CDS_LIB"pure_quanta_power"
SIZE"1B"
BOM_COST"MEM"
HDL_POWER"GND";
"A<SIZE-1..0>\NAC"20;
%"GND"
"1","(-7300,975)","0","pure_quanta_power","I952";
;
CDS_LIB"pure_quanta_power"
BOM_COST"MEM"
SIZE"1B"
HDL_POWER"GND";
"A<SIZE-1..0>\NAC"21;
%"GND"
"1","(-7050,975)","0","pure_quanta_power","I953";
;
CDS_LIB"pure_quanta_power"
BOM_COST"MEM"
SIZE"1B"
HDL_POWER"GND";
"A<SIZE-1..0>\NAC"22;
%"Q_RES"
"1","(-7025,5225)","0","pure_quanta","I957";
;
LOCATION"R1527"
$SEC"1"
CDS_SEC"1"
VALUE"4.7K"
CDS_LIB"pure_quanta"
WATTAGE"1/16W"
MATERIAL"CHIP"
TOLERANCE"5%"
PART_NUMBER"TMP_QCS24702JB38"
PACK_TYPE"0402LF";
"B"
$PN"2"37;
"A"
$PN"1"41;
%"Q_RES"
"1","(-7025,4850)","0","pure_quanta","I959";
;
$LOCATION"R1544"
CDS_LOCATION"R1544"
$SEC"1"
CDS_SEC"1"
VALUE"4.7K"
PACK_TYPE"0402LF"
PART_NUMBER"TMP_QCS24702JB38"
TOLERANCE"5%"
MATERIAL"CHIP"
WATTAGE"1/16W"
CDS_LIB"pure_quanta";
"B"
$PN"2"37;
"A"
$PN"1"27;
%"Q_RES"
"1","(-7025,4800)","0","pure_quanta","I961";
;
$LOCATION"R1545"
CDS_LOCATION"R1545"
$SEC"1"
CDS_SEC"1"
VALUE"4.7K"
PACK_TYPE"0402LF"
PART_NUMBER"TMP_QCS24702JB38"
TOLERANCE"5%"
MATERIAL"CHIP"
WATTAGE"1/16W"
CDS_LIB"pure_quanta";
"B"
$PN"2"37;
"A"
$PN"1"28;
END.
